# SCM (Grand Teton) — schematic netlist excerpt (pin names and nets, part order shuffled) for the footprints in the layout excerpt that follows; sources: Cadence DE-HDL packaged netlist, KiCad conversion of 12092022_DA0F0TMDCD0_F0T_Management_Board_D_brd_V3_OCP.brd

R361  Q_RES  120 1% CHIP  pkg 0402LF  page 20 : A = M_BMC_DDR4_MA<10> ; B = P1V2_AUX
PR522  Q_RES  100K 1% CHIP  pkg 0402LF  page 51 : A = EN_P5V_AUX ; B = GND

(kicad_pcb
	(version 20260206)
	(generator "pcbnew")
	(generator_version "10.0")
	(general
		(thickness 1.6)
		(legacy_teardrops no)
	)
	(paper "A4")
	(title_block
		(title "12092022_DA0F0TMDCD0_F0T_Management_Board_D_brd_V3_OCP.brd")
		(comment 1 "Grand Teton / footprints 61-62 of 1440")
	)
	(layers
		(0 "F.Cu" signal "TOP")
		(4 "In1.Cu" signal "GND")
		(6 "In2.Cu" signal "IN1")
		(8 "In3.Cu" signal "GND1")
		(10 "In4.Cu" signal "IN2")
		(12 "In5.Cu" signal "VCC")
		(14 "In6.Cu" signal "VCC1")
		(16 "In7.Cu" signal "IN3")
		(18 "In8.Cu" signal "GND2")
		(20 "In9.Cu" signal "IN4")
		(22 "In10.Cu" signal "GND3")
		(2 "B.Cu" signal "BOTTOM")
		(9 "F.Adhes" user "F.Adhesive")
		(11 "B.Adhes" user "B.Adhesive")
		(13 "F.Paste" user "Package Geometry/Pastemask Top")
		(15 "B.Paste" user "Package Geometry/Pastemask Bottom")
		(5 "F.SilkS" user "Ref Des/Silkscreen Top")
		(7 "B.SilkS" user "Ref Des/Silkscreen Bottom")
		(1 "F.Mask" user "Board Geometry/Soldermask Top")
		(3 "B.Mask" user "Board Geometry/Soldermask Bottom")
		(17 "Dwgs.User" user "User.Drawings")
		(19 "Cmts.User" user "User.Comments")
		(21 "Eco1.User" user "User.Eco1")
		(23 "Eco2.User" user "User.Eco2")
		(25 "Edge.Cuts" user "Board Geometry/Outline")
		(27 "Margin" user)
		(31 "F.CrtYd" user "Package Geometry/Place Bound Top")
		(29 "B.CrtYd" user "Package Geometry/Place Bound Bottom")
		(35 "F.Fab" user "Ref Des/Assembly Top")
		(33 "B.Fab" user "Ref Des/Assembly Bottom")
	)
	(footprint ""
		(layer "F.Cu")
		(at 10.739374 -52.008532 90)
		(property "Reference" "PR522"
			(at 0 0 90)
			(layer "F.SilkS")
			(hide yes)
			(effects
				(font
					(size 1.27 1.27)
				)
			)
		)
		(property "Value" ""
			(at 0 0 90)
			(layer "F.Fab")
			(effects
				(font
					(size 1.27 1.27)
				)
			)
		)
		(duplicate_pad_numbers_are_jumpers no)
		(fp_line
			(start 0.7874 -0.4064)
			(end 0.7874 0.4064)
			(stroke
				(width 0.1524)
				(type default)
			)
			(layer "F.SilkS")
		)
		(fp_line
			(start -0.7874 -0.4064)
			(end 0.7874 -0.4064)
			(stroke
				(width 0.1524)
				(type default)
			)
			(layer "F.SilkS")
		)
		(fp_line
			(start 0.7874 0.4064)
			(end -0.7874 0.4064)
			(stroke
				(width 0.1524)
				(type default)
			)
			(layer "F.SilkS")
		)
		(fp_line
			(start -0.7874 0.4064)
			(end -0.7874 -0.4064)
			(stroke
				(width 0.1524)
				(type default)
			)
			(layer "F.SilkS")
		)
		(fp_line
			(start -0.12065 -0.305054)
			(end -0.12065 -0.2794)
			(stroke
				(width 0.1)
				(type default)
			)
			(layer "F.Fab")
		)
		(fp_line
			(start -0.67945 -0.305054)
			(end -0.12065 -0.305054)
			(stroke
				(width 0.1)
				(type default)
			)
			(layer "F.Fab")
		)
		(fp_line
			(start 0.67945 -0.3048)
			(end 0.67945 0.3048)
			(stroke
				(width 0.1)
				(type default)
			)
			(layer "F.Fab")
		)
		(fp_line
			(start 0.12065 -0.3048)
			(end 0.67945 -0.3048)
			(stroke
				(width 0.1)
				(type default)
			)
			(layer "F.Fab")
		)
		(fp_line
			(start 0.12065 -0.2794)
			(end 0.12065 -0.3048)
			(stroke
				(width 0.1)
				(type default)
			)
			(layer "F.Fab")
		)
		(fp_line
			(start -0.12065 -0.2794)
			(end 0.12065 -0.2794)
			(stroke
				(width 0.1)
				(type default)
			)
			(layer "F.Fab")
		)
		(fp_line
			(start 0.120396 0.2794)
			(end -0.12065 0.2794)
			(stroke
				(width 0.1)
				(type default)
			)
			(layer "F.Fab")
		)
		(fp_line
			(start -0.12065 0.2794)
			(end -0.12065 0.3048)
			(stroke
				(width 0.1)
				(type default)
			)
			(layer "F.Fab")
		)
		(fp_line
			(start 0.67945 0.3048)
			(end 0.120396 0.3048)
			(stroke
				(width 0.1)
				(type default)
			)
			(layer "F.Fab")
		)
		(fp_line
			(start 0.120396 0.3048)
			(end 0.120396 0.2794)
			(stroke
				(width 0.1)
				(type default)
			)
			(layer "F.Fab")
		)
		(fp_line
			(start -0.12065 0.3048)
			(end -0.67945 0.3048)
			(stroke
				(width 0.1)
				(type default)
			)
			(layer "F.Fab")
		)
		(fp_line
			(start -0.67945 0.3048)
			(end -0.67945 -0.305054)
			(stroke
				(width 0.1)
				(type default)
			)
			(layer "F.Fab")
		)
		(pad "1" smd circle
			(at -0.40005 0 90)
			(size 0 0)
			(layers "F.Cu" "F.Mask" "F.Paste")
			(net "EN_P5V_AUX")
		)
		(pad "2" smd circle
			(at 0.40005 0 90)
			(size 0 0)
			(layers "F.Cu" "F.Mask" "F.Paste")
			(net "GND")
		)
	)
	(footprint ""
		(layer "F.Cu")
		(at 78.723744 -37.559488 -90)
		(property "Reference" "R361"
			(at 0 0 270)
			(layer "F.SilkS")
			(hide yes)
			(effects
				(font
					(size 1.27 1.27)
				)
			)
		)
		(property "Value" ""
			(at 0 0 270)
			(layer "F.Fab")
			(effects
				(font
					(size 1.27 1.27)
				)
			)
		)
		(duplicate_pad_numbers_are_jumpers no)
		(fp_line
			(start -0.7874 0.4064)
			(end -0.7874 -0.4064)
			(stroke
				(width 0.1524)
				(type default)
			)
			(layer "F.SilkS")
		)
		(fp_line
			(start 0.7874 0.4064)
			(end -0.7874 0.4064)
			(stroke
				(width 0.1524)
				(type default)
			)
			(layer "F.SilkS")
		)
		(fp_line
			(start -0.7874 -0.4064)
			(end 0.7874 -0.4064)
			(stroke
				(width 0.1524)
				(type default)
			)
			(layer "F.SilkS")
		)
		(fp_line
			(start 0.7874 -0.4064)
			(end 0.7874 0.4064)
			(stroke
				(width 0.1524)
				(type default)
			)
			(layer "F.SilkS")
		)
		(fp_line
			(start -0.67945 0.3048)
			(end -0.67945 -0.305054)
			(stroke
				(width 0.1)
				(type default)
			)
			(layer "F.Fab")
		)
		(fp_line
			(start -0.12065 0.3048)
			(end -0.67945 0.3048)
			(stroke
				(width 0.1)
				(type default)
			)
			(layer "F.Fab")
		)
		(fp_line
			(start 0.120396 0.3048)
			(end 0.120396 0.2794)
			(stroke
				(width 0.1)
				(type default)
			)
			(layer "F.Fab")
		)
		(fp_line
			(start 0.67945 0.3048)
			(end 0.120396 0.3048)
			(stroke
				(width 0.1)
				(type default)
			)
			(layer "F.Fab")
		)
		(fp_line
			(start -0.12065 0.2794)
			(end -0.12065 0.3048)
			(stroke
				(width 0.1)
				(type default)
			)
			(layer "F.Fab")
		)
		(fp_line
			(start 0.120396 0.2794)
			(end -0.12065 0.2794)
			(stroke
				(width 0.1)
				(type default)
			)
			(layer "F.Fab")
		)
		(fp_line
			(start -0.12065 -0.2794)
			(end 0.12065 -0.2794)
			(stroke
				(width 0.1)
				(type default)
			)
			(layer "F.Fab")
		)
		(fp_line
			(start 0.12065 -0.2794)
			(end 0.12065 -0.3048)
			(stroke
				(width 0.1)
				(type default)
			)
			(layer "F.Fab")
		)
		(fp_line
			(start 0.12065 -0.3048)
			(end 0.67945 -0.3048)
			(stroke
				(width 0.1)
				(type default)
			)
			(layer "F.Fab")
		)
		(fp_line
			(start 0.67945 -0.3048)
			(end 0.67945 0.3048)
			(stroke
				(width 0.1)
				(type default)
			)
			(layer "F.Fab")
		)
		(fp_line
			(start -0.67945 -0.305054)
			(end -0.12065 -0.305054)
			(stroke
				(width 0.1)
				(type default)
			)
			(layer "F.Fab")
		)
		(fp_line
			(start -0.12065 -0.305054)
			(end -0.12065 -0.2794)
			(stroke
				(width 0.1)
				(type default)
			)
			(layer "F.Fab")
		)
		(pad "1" smd circle
			(at -0.40005 0 270)
			(size 0 0)
			(layers "F.Cu" "F.Mask" "F.Paste")
			(net "M_BMC_DDR4_MA<10>")
		)
		(pad "2" smd circle
			(at 0.40005 0 270)
			(size 0 0)
			(layers "F.Cu" "F.Mask" "F.Paste")
			(net "P1V2_AUX")
		)
	)
)
